FILE_TYPE = MACRO_DRAWING;
SET COLOR_WIRE YELLOW;
SET COLOR_PROP ORANGE;
SET COLOR_DOT WHITE;
SET COLOR_ARC YELLOW;
SET COLOR_BODY GREEN;
SET COLOR_NOTE PURPLE;
SET PROP_DISPLAY VALUE;
SET PAGE_NUMBER P234;
FORCEADD OFFPAGE..1
(9050 3125);
FORCEPROP 2 LAST $XR3 259 
J 0
(8408 3125);
DISPLAY 0.638298 (8408 3125);
PAINT MONO (8408 3125);
FORCEPROP 2 LAST $XR2 214 
J 0
(8528 3125);
DISPLAY 0.638298 (8528 3125);
PAINT MONO (8528 3125);
FORCEPROP 2 LAST $XR1 305 
J 0
(8648 3125);
DISPLAY 0.638298 (8648 3125);
PAINT MONO (8648 3125);
FORCEPROP 2 LAST $XR0 301 
J 0
(8768 3125);
DISPLAY 0.638298 (8768 3125);
PAINT MONO (8768 3125);
FORCEPROP 2 LAST PATH I1
J 0
(8800 3175);
DISPLAY 1.021277 (8800 3175);
DISPLAY INVISIBLE (8800 3175);
FORCEPROP 1 LAST COMMENT_BODY TRUE
J 0
(9175 3025);
DISPLAY 0.872340 (9175 3025);
PAINT GREEN (9175 3025);
DISPLAY INVISIBLE (9175 3025);
FORCEPROP 1 LAST OFFPAGE TRUE
J 0
(9375 3000);
DISPLAY 0.872340 (9375 3000);
PAINT GREEN (9375 3000);
DISPLAY INVISIBLE (9375 3000);
FORCEPROP 2 LAST CDS_LIB standard
J 0
(9050 3125);
DISPLAY INVISIBLE (9050 3125);
FORCEADD Q_RES..2
(14600 4050);
FORCEPROP 1 LAST PART_NUMBER CS24702JB10
J 0
(14640 3925);
DISPLAY 0.510638 (14640 3925);
DISPLAY INVISIBLE (14640 3925);
FORCEPROP 1 LAST VALUE 4.7K
J 0
(14645 4125);
DISPLAY 0.510638 (14645 4125);
FORCEPROP 1 LAST TOLERANCE 5%
J 0
(14645 4075);
DISPLAY 0.510638 (14645 4075);
FORCEPROP 1 LAST PACK_TYPE 0402LF
J 0
(14640 3875);
DISPLAY 0.510638 (14640 3875);
FORCEPROP 1 LAST MATERIAL CHIP
J 0
(14640 3975);
DISPLAY 0.510638 (14640 3975);
FORCEPROP 1 LAST WATTAGE 1/16W
J 0
(14640 4025);
DISPLAY 0.510638 (14640 4025);
FORCEPROP 1 LAST $LOCATION R2530
J 0
(14645 4175);
DISPLAY 0.978723 (14645 4175);
FORCEPROP 1 LASTPIN (14600 4150) $PN 1
J 0
(14605 4112);
DISPLAY 0.787234 (14605 4112);
PAINT MONO (14605 4112);
FORCEPROP 1 LASTPIN (14600 3950) $PN 2
J 0
(14605 3960);
DISPLAY 0.787234 (14605 3960);
PAINT MONO (14605 3960);
FORCEPROP 1 LAST PATH I10
J 0
(14650 4225);
DISPLAY 0.978723 (14650 4225);
PAINT WHITE (14650 4225);
DISPLAY INVISIBLE (14650 4225);
FORCEPROP 2 LAST CDS_LIB pure_quanta
J 0
(14600 4050);
DISPLAY INVISIBLE (14600 4050);
FORCEPROP 0 LAST CDS_LOCATION R2530
J 0
(14650 4225);
DISPLAY 1.021277 (14650 4225);
DISPLAY INVISIBLE (14650 4225);
FORCEPROP 0 LAST $SEC 1
J 0
(14650 4225);
DISPLAY 0.680851 (14650 4225);
PAINT MONO (14650 4225);
DISPLAY INVISIBLE (14650 4225);
FORCEPROP 0 LAST CDS_SEC 1
J 0
(14650 4225);
DISPLAY 1.021277 (14650 4225);
DISPLAY INVISIBLE (14650 4225);
FORCEADD UNIVERSAL_POWER..1
(14600 4300);
FORCEPROP 3 LASTPIN (14600 4250) SIG_NAME P12V_AUX\g
J 0
(14610 4260);
DISPLAY 0.659574 (14610 4260);
PAINT MONO (14610 4260);
DISPLAY INVISIBLE (14610 4260);
FORCEPROP 1 LAST HDL_POWER P12V_AUX
J 1
(14600 4350);
DISPLAY 0.872340 (14600 4350);
PAINT GREEN (14600 4350);
FORCEPROP 1 LAST PATH I11
J 0
(14650 4325);
DISPLAY 0.872340 (14650 4325);
PAINT AQUA (14650 4325);
DISPLAY INVISIBLE (14650 4325);
FORCEPROP 2 LAST CDS_LIB logical_power
J 0
(14600 4300);
DISPLAY INVISIBLE (14600 4300);
FORCEADD MOSFET_NCH_GDS_ESD_PROTECTED..1
(14000 3450);
FORCEPROP 1 LAST PART_NUMBER BAM70020002
J 0
(14142 3362);
DISPLAY 0.723404 (14142 3362);
PAINT GREEN (14142 3362);
DISPLAY INVISIBLE (14142 3362);
FORCEPROP 2 LAST PART_TYPE SMLF
J 0
(14150 3550);
DISPLAY 0.680851 (14150 3550);
FORCEPROP 2 LAST VALUE 2N7002K
J 0
(14150 3500);
DISPLAY 0.680851 (14150 3500);
FORCEPROP 1 LAST MATERIAL IC
J 0
(14142 3305);
DISPLAY 0.723404 (14142 3305);
PAINT GREEN (14142 3305);
FORCEPROP 1 LAST LOCATION Q54
J 0
(14142 3414);
DISPLAY 0.723404 (14142 3414);
PAINT GREEN (14142 3414);
FORCEPROP 0 LASTPIN (14025 3650) $PN D
R 1
J 0
(14015 3660);
DISPLAY 0.680851 (14015 3660);
PAINT MONO (14015 3660);
FORCEPROP 0 LASTPIN (13825 3450) $PN G
J 2
(13815 3460);
DISPLAY 0.680851 (13815 3460);
PAINT MONO (13815 3460);
FORCEPROP 0 LASTPIN (14025 3250) $PN S
R 1
J 2
(14015 3240);
DISPLAY 0.680851 (14015 3240);
PAINT MONO (14015 3240);
FORCEPROP 1 LAST NEEDS_NO_SIZE TRUE
J 0
(14125 3340);
DISPLAY 0.723404 (14125 3340);
PAINT GREEN (14125 3340);
DISPLAY INVISIBLE (14125 3340);
FORCEPROP 1 LAST CDS_LMAN_SYM_OUTLINE -125,150,125,-150
J 0
(14000 3450);
DISPLAY 0.468085 (14000 3450);
PAINT GREEN (14000 3450);
DISPLAY INVISIBLE (14000 3450);
FORCEPROP 1 LAST PATH I14
J 0
(14125 3300);
DISPLAY 0.723404 (14125 3300);
PAINT GREEN (14125 3300);
DISPLAY INVISIBLE (14125 3300);
FORCEPROP 2 LAST CDS_LIB pure_quanta
J 2
(14000 3450);
DISPLAY INVISIBLE (14000 3450);
FORCEPROP 0 LAST $SEC 1
J 0
(14150 3600);
DISPLAY 0.680851 (14150 3600);
PAINT MONO (14150 3600);
DISPLAY INVISIBLE (14150 3600);
FORCEPROP 0 LAST CDS_SEC 1
J 0
(14150 3600);
DISPLAY 1.021277 (14150 3600);
DISPLAY INVISIBLE (14150 3600);
FORCEADD UNIVERSAL_GND..1
(14025 3050);
FORCEPROP 3 LASTPIN (14025 3100) SIG_NAME GND\g
J 0
(14035 3110);
DISPLAY 0.659574 (14035 3110);
PAINT MONO (14035 3110);
DISPLAY INVISIBLE (14035 3110);
FORCEPROP 1 LAST PATH I15
J 0
(14100 3050);
DISPLAY 0.872340 (14100 3050);
PAINT AQUA (14100 3050);
DISPLAY INVISIBLE (14100 3050);
FORCEPROP 1 LAST HDL_POWER GND
J 1
(14050 2975);
DISPLAY 0.872340 (14050 2975);
PAINT GREEN (14050 2975);
DISPLAY INVISIBLE (14050 2975);
FORCEPROP 2 LAST CDS_LIB logical_power
J 0
(14025 3050);
DISPLAY INVISIBLE (14025 3050);
FORCEADD Q_RES..1
(10325 3125);
FORCEPROP 1 LAST PART_NUMBER CS00002JB13
J 0
(10450 3150);
DISPLAY 0.319149 (10450 3150);
DISPLAY INVISIBLE (10450 3150);
FORCEPROP 1 LAST VALUE 0
J 2
(10475 3125);
DISPLAY 0.404255 (10475 3125);
FORCEPROP 1 LAST PACK_TYPE 0402LF
J 0
(10450 3175);
DISPLAY 0.319149 (10450 3175);
FORCEPROP 1 LAST WATTAGE 1/16W
J 2
(10625 3175);
DISPLAY 0.319149 (10625 3175);
FORCEPROP 1 LAST MATERIAL CHIP
J 0
(10575 3125);
DISPLAY 0.404255 (10575 3125);
FORCEPROP 1 LAST TOLERANCE 5%
J 0
(10500 3125);
DISPLAY 0.404255 (10500 3125);
FORCEPROP 1 LAST $LOCATION R2531
J 0
(10075 3125);
DISPLAY 0.787234 (10075 3125);
FORCEPROP 1 LASTPIN (10225 3125) $PN 1
J 0
(10237 3137);
DISPLAY 0.787234 (10237 3137);
PAINT MONO (10237 3137);
FORCEPROP 1 LASTPIN (10425 3125) $PN 2
J 0
(10387 3137);
DISPLAY 0.787234 (10387 3137);
PAINT MONO (10387 3137);
FORCEPROP 1 LAST PATH I3
J 0
(10275 3275);
DISPLAY 0.978723 (10275 3275);
PAINT WHITE (10275 3275);
DISPLAY INVISIBLE (10275 3275);
FORCEPROP 2 LAST CDS_LIB pure_quanta
J 0
(10325 3125);
DISPLAY INVISIBLE (10325 3125);
FORCEPROP 0 LAST CDS_LOCATION R2531
J 0
(10625 3200);
DISPLAY 1.021277 (10625 3200);
DISPLAY INVISIBLE (10625 3200);
FORCEPROP 0 LAST $SEC 1
J 0
(10625 3200);
DISPLAY 0.680851 (10625 3200);
PAINT MONO (10625 3200);
DISPLAY INVISIBLE (10625 3200);
FORCEPROP 0 LAST CDS_SEC 1
J 0
(10625 3200);
DISPLAY 1.021277 (10625 3200);
DISPLAY INVISIBLE (10625 3200);
FORCEADD UNIVERSAL_GND..1
(11650 2775);
FORCEPROP 3 LASTPIN (11650 2825) SIG_NAME GND\g
J 0
(11660 2835);
DISPLAY 0.659574 (11660 2835);
PAINT MONO (11660 2835);
DISPLAY INVISIBLE (11660 2835);
FORCEPROP 1 LAST PATH I5
J 0
(11725 2775);
DISPLAY 0.872340 (11725 2775);
PAINT AQUA (11725 2775);
DISPLAY INVISIBLE (11725 2775);
FORCEPROP 2 LAST CDS_LIB logical_power
J 0
(11650 2775);
DISPLAY INVISIBLE (11650 2775);
FORCEPROP 1 LAST HDL_POWER GND
J 1
(11675 2700);
DISPLAY 0.872340 (11675 2700);
PAINT GREEN (11675 2700);
DISPLAY INVISIBLE (11675 2700);
FORCEADD MOSFET_NCH_GDS_ESD_PROTECTED..1
(11625 3125);
FORCEPROP 1 LAST PART_NUMBER BAM70020002
J 0
(11767 3037);
DISPLAY 0.723404 (11767 3037);
PAINT GREEN (11767 3037);
DISPLAY INVISIBLE (11767 3037);
FORCEPROP 1 LAST MATERIAL IC
J 0
(11767 2980);
DISPLAY 0.723404 (11767 2980);
PAINT GREEN (11767 2980);
FORCEPROP 2 LAST VALUE 2N7002K
J 0
(11775 3175);
DISPLAY 0.680851 (11775 3175);
FORCEPROP 2 LAST PART_TYPE SMLF
J 0
(11775 3225);
DISPLAY 0.680851 (11775 3225);
FORCEPROP 1 LAST $LOCATION U158
J 0
(11767 3089);
DISPLAY 0.723404 (11767 3089);
PAINT GREEN (11767 3089);
FORCEPROP 0 LASTPIN (11650 3325) $PN D
R 1
J 0
(11640 3335);
DISPLAY 0.680851 (11640 3335);
PAINT MONO (11640 3335);
FORCEPROP 0 LASTPIN (11450 3125) $PN G
J 2
(11440 3135);
DISPLAY 0.680851 (11440 3135);
PAINT MONO (11440 3135);
FORCEPROP 0 LASTPIN (11650 2925) $PN S
R 1
J 2
(11640 2915);
DISPLAY 0.680851 (11640 2915);
PAINT MONO (11640 2915);
FORCEPROP 1 LAST PATH I6
J 0
(11750 2975);
DISPLAY 0.723404 (11750 2975);
PAINT GREEN (11750 2975);
DISPLAY INVISIBLE (11750 2975);
FORCEPROP 1 LAST NEEDS_NO_SIZE TRUE
J 0
(11750 3015);
DISPLAY 0.723404 (11750 3015);
PAINT GREEN (11750 3015);
DISPLAY INVISIBLE (11750 3015);
FORCEPROP 1 LAST CDS_LMAN_SYM_OUTLINE -125,150,125,-150
J 0
(11625 3125);
DISPLAY 0.468085 (11625 3125);
PAINT GREEN (11625 3125);
DISPLAY INVISIBLE (11625 3125);
FORCEPROP 2 LAST CDS_LIB pure_quanta
J 0
(11625 3125);
DISPLAY INVISIBLE (11625 3125);
FORCEPROP 0 LAST CDS_LOCATION U158
J 0
(11775 3275);
DISPLAY 1.021277 (11775 3275);
DISPLAY INVISIBLE (11775 3275);
FORCEPROP 0 LAST $SEC 1
J 0
(11775 3275);
DISPLAY 0.680851 (11775 3275);
PAINT MONO (11775 3275);
DISPLAY INVISIBLE (11775 3275);
FORCEPROP 0 LAST CDS_SEC 1
J 0
(11775 3275);
DISPLAY 1.021277 (11775 3275);
DISPLAY INVISIBLE (11775 3275);
FORCEADD Q_RES..1
(12575 3450);
FORCEPROP 1 LAST PART_NUMBER CS00002JB13
J 0
(12700 3475);
DISPLAY 0.319149 (12700 3475);
DISPLAY INVISIBLE (12700 3475);
FORCEPROP 1 LAST MATERIAL CHIP
J 0
(12825 3450);
DISPLAY 0.404255 (12825 3450);
FORCEPROP 1 LAST PACK_TYPE 0402LF
J 0
(12700 3500);
DISPLAY 0.319149 (12700 3500);
FORCEPROP 1 LAST WATTAGE 1/16W
J 2
(12875 3500);
DISPLAY 0.319149 (12875 3500);
FORCEPROP 1 LAST VALUE 0
J 2
(12725 3450);
DISPLAY 0.404255 (12725 3450);
FORCEPROP 1 LAST TOLERANCE 5%
J 0
(12750 3450);
DISPLAY 0.404255 (12750 3450);
FORCEPROP 1 LAST $LOCATION R2529
J 0
(12325 3450);
DISPLAY 0.787234 (12325 3450);
FORCEPROP 1 LASTPIN (12475 3450) $PN 1
J 0
(12487 3462);
DISPLAY 0.787234 (12487 3462);
PAINT MONO (12487 3462);
FORCEPROP 1 LASTPIN (12675 3450) $PN 2
J 0
(12637 3462);
DISPLAY 0.787234 (12637 3462);
PAINT MONO (12637 3462);
FORCEPROP 1 LAST PATH I7
J 0
(12525 3600);
DISPLAY 0.978723 (12525 3600);
PAINT WHITE (12525 3600);
DISPLAY INVISIBLE (12525 3600);
FORCEPROP 2 LAST CDS_LIB pure_quanta
J 0
(12575 3450);
DISPLAY INVISIBLE (12575 3450);
FORCEPROP 0 LAST CDS_LOCATION R2529
J 0
(12875 3525);
DISPLAY 1.021277 (12875 3525);
DISPLAY INVISIBLE (12875 3525);
FORCEPROP 0 LAST $SEC 1
J 0
(12875 3525);
DISPLAY 0.680851 (12875 3525);
PAINT MONO (12875 3525);
DISPLAY INVISIBLE (12875 3525);
FORCEPROP 0 LAST CDS_SEC 1
J 0
(12875 3525);
DISPLAY 1.021277 (12875 3525);
DISPLAY INVISIBLE (12875 3525);
FORCEADD Q_RES..2
(11650 3850);
FORCEPROP 1 LAST PART_NUMBER CS41002FB09
J 0
(11690 3725);
DISPLAY 0.510638 (11690 3725);
DISPLAY INVISIBLE (11690 3725);
FORCEPROP 1 LAST WATTAGE 1/16W
J 0
(11690 3825);
DISPLAY 0.510638 (11690 3825);
FORCEPROP 1 LAST MATERIAL CHIP
J 0
(11690 3775);
DISPLAY 0.510638 (11690 3775);
FORCEPROP 1 LAST TOLERANCE 1%
J 0
(11695 3875);
DISPLAY 0.510638 (11695 3875);
FORCEPROP 1 LAST VALUE 100K
J 0
(11695 3925);
DISPLAY 0.510638 (11695 3925);
FORCEPROP 1 LAST PACK_TYPE 0402LF
J 0
(11690 3675);
DISPLAY 0.510638 (11690 3675);
FORCEPROP 1 LAST $LOCATION R2528
J 0
(11695 3975);
DISPLAY 0.978723 (11695 3975);
FORCEPROP 1 LASTPIN (11650 3950) $PN 1
J 0
(11655 3912);
DISPLAY 0.787234 (11655 3912);
PAINT MONO (11655 3912);
FORCEPROP 1 LASTPIN (11650 3750) $PN 2
J 0
(11655 3760);
DISPLAY 0.787234 (11655 3760);
PAINT MONO (11655 3760);
FORCEPROP 1 LAST PATH I8
J 0
(11700 4025);
DISPLAY 0.978723 (11700 4025);
PAINT WHITE (11700 4025);
DISPLAY INVISIBLE (11700 4025);
FORCEPROP 2 LAST CDS_LIB pure_quanta
J 0
(11650 3850);
DISPLAY INVISIBLE (11650 3850);
FORCEPROP 0 LAST CDS_LOCATION R2528
J 0
(11700 4025);
DISPLAY 1.021277 (11700 4025);
DISPLAY INVISIBLE (11700 4025);
FORCEPROP 0 LAST $SEC 1
J 0
(11700 4025);
DISPLAY 0.680851 (11700 4025);
PAINT MONO (11700 4025);
DISPLAY INVISIBLE (11700 4025);
FORCEPROP 0 LAST CDS_SEC 1
J 0
(11700 4025);
DISPLAY 1.021277 (11700 4025);
DISPLAY INVISIBLE (11700 4025);
FORCEADD UNIVERSAL_POWER..1
(11650 4100);
FORCEPROP 3 LASTPIN (11650 4050) SIG_NAME P12V_AUX\g
J 0
(11660 4060);
DISPLAY 0.659574 (11660 4060);
PAINT MONO (11660 4060);
DISPLAY INVISIBLE (11660 4060);
FORCEPROP 1 LAST HDL_POWER P12V_AUX
J 1
(11650 4150);
DISPLAY 0.872340 (11650 4150);
PAINT GREEN (11650 4150);
FORCEPROP 1 LAST PATH I9
J 0
(11700 4125);
DISPLAY 0.872340 (11700 4125);
PAINT AQUA (11700 4125);
DISPLAY INVISIBLE (11700 4125);
FORCEPROP 2 LAST CDS_LIB logical_power
J 0
(11650 4100);
DISPLAY INVISIBLE (11650 4100);
FORCEADD QUANTA_TITLE_BLOCK_C..1
(16850 -1225);
FORCEPROP 0 LAST CDS_CON_LAST_MODIFIED Fri Aug 25 14:04:17 2023
J 0
(14965 -1210);
PAINT MONO (14965 -1210);
DISPLAY INVISIBLE (14965 -1210);
FORCEPROP 1 LAST CUSTOM_TXT_CDS <CON_LAST_MODIFIED>
J 0
(14965 -1210);
DISPLAY 0.978723 (14965 -1210);
FORCEPROP 2 LAST CUSTOM_TXT_CDS <XR_PAGE_TITLE>
J 0
(8960 4025);
DISPLAY 0.638298 (8960 4025);
PAINT PINK (8960 4025);
DISPLAY INVISIBLE (8960 4025);
FORCEPROP 1 LAST CUSTOM_TXT_CDS <NAME_2>
J 0
(13675 -1175);
FORCEPROP 1 LAST CUSTOM_TXT_CDS <NAME_1>
J 0
(13675 -1050);
FORCEPROP 1 LAST CUSTOM_TXT_CDS <Q_NUMBER>
J 0
(15447 -1122);
DISPLAY 1.212766 (15447 -1122);
FORCEPROP 1 LAST CUSTOM_TXT_CDS <Q_PROJ>
J 0
(14468 -1123);
DISPLAY 1.212766 (14468 -1123);
FORCEPROP 1 LAST CUSTOM_TXT_CDS <Q_REV>
J 0
(16666 -1122);
DISPLAY 1.212766 (16666 -1122);
FORCEPROP 1 LAST CUSTOM_TXT_CDS <CON_PAGE_NUM> OF <CON_TOTAL_PAGES>
J 0
(16404 -1207);
DISPLAY 0.978723 (16404 -1207);
FORCEPROP 1 LAST Q_TITLE PSU POWER CONNECTORS
J 0
(7584 -1199);
DISPLAY 2.446809 (7584 -1199);
PAINT GREEN (7584 -1199);
FORCEPROP 1 LAST Q_DEPT 
J 1
(13087 -1176);
DISPLAY 1.957447 (13087 -1176);
PAINT GREEN (13087 -1176);
FORCEPROP 2 LAST CDS_XR_PAGE_TITLE CR-247 : @S9S_MB_2U_LIB.S9S_MB_2U(SCH_1):PAGE247
J 0
(8960 4025);
DISPLAY 0.638298 (8960 4025);
PAINT PINK (8960 4025);
DISPLAY INVISIBLE (8960 4025);
FORCEPROP 2 LAST PAGE_BORDER TRUE
J 0
(8960 4025);
DISPLAY 0.638298 (8960 4025);
PAINT PINK (8960 4025);
DISPLAY INVISIBLE (8960 4025);
FORCEPROP 1 LAST COMMENT_BODY TRUE
J 0
(16862 -1238);
DISPLAY 0.978723 (16862 -1238);
PAINT GREEN (16862 -1238);
DISPLAY INVISIBLE (16862 -1238);
FORCEPROP 1 LAST CDS_LMAN_SYM_OUTLINE -9475,6775,100,-125
J 0
(16850 -1225);
DISPLAY 0.468085 (16850 -1225);
PAINT GREEN (16850 -1225);
DISPLAY INVISIBLE (16850 -1225);
FORCEPROP 2 LAST CDS_LIB pure_quanta
J 0
(16850 -1225);
PAINT MONO (16850 -1225);
DISPLAY INVISIBLE (16850 -1225);
WIRE 16 -1 (11650 4050)(11650 3950);
WIRE 16 -1 (14600 4250)(14600 4150);
WIRE 16 -1 (11650 2825)(11650 2925);
WIRE 16 -1 (14025 3250)(14025 3100);
WIRE 16 -1 (10425 3125)(11450 3125);
FORCEPROP 2 LAST SIG_NAME FM_P12V_HSC_EN_R
J 0
(10790 3135);
DISPLAY 0.638298 (10790 3135);
PAINT WHITE (10790 3135);
WIRE 16 -1 (9100 3125)(10225 3125);
FORCEPROP 2 LAST SIG_NAME MB0_P12V_STBY_PWRGD
J 0
(9265 3135);
DISPLAY 0.638298 (9265 3135);
PAINT WHITE (9265 3135);
WIRE 16 -1 (11650 3325)(11650 3450);
WIRE 16 -1 (12475 3450)(11650 3450);
FORCEPROP 2 LAST SIG_NAME FM_P12V_HSC_EN_N
J 0
(11715 3460);
DISPLAY 0.638298 (11715 3460);
PAINT WHITE (11715 3460);
WIRE 16 -1 (11650 3750)(11650 3450);
WIRE 16 -1 (14025 3800)(14025 3650);
WIRE 16 -1 (14600 3800)(14025 3800);
FORCEPROP 2 LAST SIG_NAME P12V_AUX_BLEEDING
J 0
(14115 3810);
DISPLAY 0.553191 (14115 3810);
PAINT WHITE (14115 3810);
WIRE 16 -1 (14600 3800)(14600 3950);
WIRE 16 -1 (12675 3450)(13825 3450);
FORCEPROP 2 LAST SIG_NAME FM_P12V_HSC_EN_R_N
J 0
(13065 3460);
DISPLAY 0.638298 (13065 3460);
PAINT WHITE (13065 3460);
DOT 1 (11650 3450);
FORCENOTE
20210616 MODIFY FOR GT
(7850 5200) 0;
DISPLAY LEFT (7850 5200);
DISPLAY 2.510638 (7850 5200);
PAINT PINK (7850 5200);
QUIT
